# S9S_MB_2U (Grand Teton) — schematic netlist excerpt (pin names and nets, part order shuffled) for the footprints in the layout excerpt that follows; sources: Cadence DE-HDL packaged netlist, KiCad conversion of 03242023_DA0F0TMBIJ0_F0T_Motherboard_J_brd_V01_OCP.brd

R4139  Q_RES  4.7K 5% CHIP  pkg 0402LF  page 146 : A = P3V3_AUX ; B = PRSNT_CABLE_GPU_A2
C431  Q_CAP  22UF 4V 20% X6S  pkg C0402  page 77 : A = PVCCFA_EHV_FIVRA_CPU1 ; B = GND

(kicad_pcb
	(version 20260206)
	(generator "pcbnew")
	(generator_version "10.0")
	(general
		(thickness 1.6)
		(legacy_teardrops no)
	)
	(paper "A4")
	(title_block
		(title "03242023_DA0F0TMBIJ0_F0T_Motherboard_J_brd_V01_OCP.brd")
		(comment 1 "Grand Teton / footprints 187-188 of 6105")
	)
	(layers
		(0 "F.Cu" signal "TOP")
		(4 "In1.Cu" signal "GND")
		(6 "In2.Cu" signal "IN1")
		(8 "In3.Cu" signal "GND1")
		(10 "In4.Cu" signal "IN2")
		(12 "In5.Cu" signal "GND2")
		(14 "In6.Cu" signal "IN3")
		(16 "In7.Cu" signal "GND3")
		(18 "In8.Cu" signal "VCC")
		(20 "In9.Cu" signal "VCC1")
		(22 "In10.Cu" signal "GND4")
		(24 "In11.Cu" signal "IN4")
		(26 "In12.Cu" signal "GND5")
		(28 "In13.Cu" signal "IN5")
		(30 "In14.Cu" signal "GND6")
		(32 "In15.Cu" signal "IN6")
		(34 "In16.Cu" signal "GND7")
		(2 "B.Cu" signal "BOTTOM")
		(9 "F.Adhes" user "F.Adhesive")
		(11 "B.Adhes" user "B.Adhesive")
		(13 "F.Paste" user "Package Geometry/Pastemask Top")
		(15 "B.Paste" user "Package Geometry/Pastemask Bottom")
		(5 "F.SilkS" user "Ref Des/Silkscreen Top")
		(7 "B.SilkS" user "Ref Des/Silkscreen Bottom")
		(1 "F.Mask" user "Board Geometry/Soldermask Top")
		(3 "B.Mask" user "Board Geometry/Soldermask Bottom")
		(17 "Dwgs.User" user "User.Drawings")
		(19 "Cmts.User" user "User.Comments")
		(21 "Eco1.User" user "User.Eco1")
		(23 "Eco2.User" user "User.Eco2")
		(25 "Edge.Cuts" user "Board Geometry/Outline")
		(27 "Margin" user)
		(31 "F.CrtYd" user "Package Geometry/Place Bound Top")
		(29 "B.CrtYd" user "Package Geometry/Place Bound Bottom")
		(35 "F.Fab" user "Ref Des/Assembly Top")
		(33 "B.Fab" user "Ref Des/Assembly Bottom")
	)
	(footprint ""
		(layer "F.Cu")
		(at 104.347264 -238.162592 -90)
		(property "Reference" "C431"
			(at 0 0 270)
			(layer "F.SilkS")
			(hide yes)
			(effects
				(font
					(size 1.27 1.27)
				)
			)
		)
		(property "Value" ""
			(at 0 0 270)
			(layer "F.Fab")
			(effects
				(font
					(size 1.27 1.27)
				)
			)
		)
		(duplicate_pad_numbers_are_jumpers no)
		(fp_line
			(start -0.7874 0.4064)
			(end -0.7874 -0.4064)
			(stroke
				(width 0.1524)
				(type default)
			)
			(layer "F.SilkS")
		)
		(fp_line
			(start 0.7874 0.4064)
			(end -0.7874 0.4064)
			(stroke
				(width 0.1524)
				(type default)
			)
			(layer "F.SilkS")
		)
		(fp_line
			(start -0.7874 -0.4064)
			(end 0.7874 -0.4064)
			(stroke
				(width 0.1524)
				(type default)
			)
			(layer "F.SilkS")
		)
		(fp_line
			(start 0.7874 -0.4064)
			(end 0.7874 0.4064)
			(stroke
				(width 0.1524)
				(type default)
			)
			(layer "F.SilkS")
		)
		(fp_line
			(start -0.67945 0.3048)
			(end -0.67945 -0.305054)
			(stroke
				(width 0.1)
				(type default)
			)
			(layer "F.Fab")
		)
		(fp_line
			(start -0.12065 0.3048)
			(end -0.67945 0.3048)
			(stroke
				(width 0.1)
				(type default)
			)
			(layer "F.Fab")
		)
		(fp_line
			(start 0.120396 0.3048)
			(end 0.120396 0.2794)
			(stroke
				(width 0.1)
				(type default)
			)
			(layer "F.Fab")
		)
		(fp_line
			(start 0.67945 0.3048)
			(end 0.120396 0.3048)
			(stroke
				(width 0.1)
				(type default)
			)
			(layer "F.Fab")
		)
		(fp_line
			(start -0.12065 0.2794)
			(end -0.12065 0.3048)
			(stroke
				(width 0.1)
				(type default)
			)
			(layer "F.Fab")
		)
		(fp_line
			(start 0.120396 0.2794)
			(end -0.12065 0.2794)
			(stroke
				(width 0.1)
				(type default)
			)
			(layer "F.Fab")
		)
		(fp_line
			(start -0.12065 -0.2794)
			(end 0.12065 -0.2794)
			(stroke
				(width 0.1)
				(type default)
			)
			(layer "F.Fab")
		)
		(fp_line
			(start 0.12065 -0.2794)
			(end 0.12065 -0.3048)
			(stroke
				(width 0.1)
				(type default)
			)
			(layer "F.Fab")
		)
		(fp_line
			(start 0.12065 -0.3048)
			(end 0.67945 -0.3048)
			(stroke
				(width 0.1)
				(type default)
			)
			(layer "F.Fab")
		)
		(fp_line
			(start 0.67945 -0.3048)
			(end 0.67945 0.3048)
			(stroke
				(width 0.1)
				(type default)
			)
			(layer "F.Fab")
		)
		(fp_line
			(start -0.67945 -0.305054)
			(end -0.12065 -0.305054)
			(stroke
				(width 0.1)
				(type default)
			)
			(layer "F.Fab")
		)
		(fp_line
			(start -0.12065 -0.305054)
			(end -0.12065 -0.2794)
			(stroke
				(width 0.1)
				(type default)
			)
			(layer "F.Fab")
		)
		(pad "1" smd circle
			(at -0.40005 0 270)
			(size 0 0)
			(layers "F.Cu" "F.Mask" "F.Paste")
			(net "PVCCFA_EHV_FIVRA_CPU1")
		)
		(pad "2" smd circle
			(at 0.40005 0 270)
			(size 0 0)
			(layers "F.Cu" "F.Mask" "F.Paste")
			(net "GND")
		)
	)
	(footprint ""
		(layer "F.Cu")
		(at 306.516024 -438.120536 -90)
		(property "Reference" "R4139"
			(at 0 0 270)
			(layer "F.SilkS")
			(hide yes)
			(effects
				(font
					(size 1.27 1.27)
				)
			)
		)
		(property "Value" ""
			(at 0 0 270)
			(layer "F.Fab")
			(effects
				(font
					(size 1.27 1.27)
				)
			)
		)
		(duplicate_pad_numbers_are_jumpers no)
		(fp_line
			(start -0.7874 0.4064)
			(end -0.7874 -0.4064)
			(stroke
				(width 0.1524)
				(type default)
			)
			(layer "F.SilkS")
		)
		(fp_line
			(start 0.7874 0.4064)
			(end -0.7874 0.4064)
			(stroke
				(width 0.1524)
				(type default)
			)
			(layer "F.SilkS")
		)
		(fp_line
			(start -0.7874 -0.4064)
			(end 0.7874 -0.4064)
			(stroke
				(width 0.1524)
				(type default)
			)
			(layer "F.SilkS")
		)
		(fp_line
			(start 0.7874 -0.4064)
			(end 0.7874 0.4064)
			(stroke
				(width 0.1524)
				(type default)
			)
			(layer "F.SilkS")
		)
		(fp_line
			(start -0.67945 0.3048)
			(end -0.67945 -0.305054)
			(stroke
				(width 0.1)
				(type default)
			)
			(layer "F.Fab")
		)
		(fp_line
			(start -0.12065 0.3048)
			(end -0.67945 0.3048)
			(stroke
				(width 0.1)
				(type default)
			)
			(layer "F.Fab")
		)
		(fp_line
			(start 0.120396 0.3048)
			(end 0.120396 0.2794)
			(stroke
				(width 0.1)
				(type default)
			)
			(layer "F.Fab")
		)
		(fp_line
			(start 0.67945 0.3048)
			(end 0.120396 0.3048)
			(stroke
				(width 0.1)
				(type default)
			)
			(layer "F.Fab")
		)
		(fp_line
			(start -0.12065 0.2794)
			(end -0.12065 0.3048)
			(stroke
				(width 0.1)
				(type default)
			)
			(layer "F.Fab")
		)
		(fp_line
			(start 0.120396 0.2794)
			(end -0.12065 0.2794)
			(stroke
				(width 0.1)
				(type default)
			)
			(layer "F.Fab")
		)
		(fp_line
			(start -0.12065 -0.2794)
			(end 0.12065 -0.2794)
			(stroke
				(width 0.1)
				(type default)
			)
			(layer "F.Fab")
		)
		(fp_line
			(start 0.12065 -0.2794)
			(end 0.12065 -0.3048)
			(stroke
				(width 0.1)
				(type default)
			)
			(layer "F.Fab")
		)
		(fp_line
			(start 0.12065 -0.3048)
			(end 0.67945 -0.3048)
			(stroke
				(width 0.1)
				(type default)
			)
			(layer "F.Fab")
		)
		(fp_line
			(start 0.67945 -0.3048)
			(end 0.67945 0.3048)
			(stroke
				(width 0.1)
				(type default)
			)
			(layer "F.Fab")
		)
		(fp_line
			(start -0.67945 -0.305054)
			(end -0.12065 -0.305054)
			(stroke
				(width 0.1)
				(type default)
			)
			(layer "F.Fab")
		)
		(fp_line
			(start -0.12065 -0.305054)
			(end -0.12065 -0.2794)
			(stroke
				(width 0.1)
				(type default)
			)
			(layer "F.Fab")
		)
		(pad "1" smd circle
			(at -0.40005 0 270)
			(size 0 0)
			(layers "F.Cu" "F.Mask" "F.Paste")
			(net "P3V3_AUX")
		)
		(pad "2" smd circle
			(at 0.40005 0 270)
			(size 0 0)
			(layers "F.Cu" "F.Mask" "F.Paste")
			(net "PRSNT_CABLE_GPU_A2")
		)
	)
)
